(kicad_pcb
	(version 20260206)
	(generator "pcbnew")
	(generator_version "10.0")
	(general
		(thickness 1.6)
		(legacy_teardrops no)
	)
	(paper "A4")
	(title_block
		(title "04192023_DAF0TMB3IC0_F0TG_MB_C_brd_V02_OCP.brd")
		(comment 1 "Grand Teton / footprints 4762-4767 of 8354")
	)
	(layers
		(0 "F.Cu" signal "TOP")
		(4 "In1.Cu" signal "GND")
		(6 "In2.Cu" signal "IN1")
		(8 "In3.Cu" signal "GND1")
		(10 "In4.Cu" signal "IN2")
		(12 "In5.Cu" signal "GND2")
		(14 "In6.Cu" signal "IN3")
		(16 "In7.Cu" signal "GND3")
		(18 "In8.Cu" signal "VCC")
		(20 "In9.Cu" signal "VCC1")
		(22 "In10.Cu" signal "GND4")
		(24 "In11.Cu" signal "IN4")
		(26 "In12.Cu" signal "GND5")
		(28 "In13.Cu" signal "IN5")
		(30 "In14.Cu" signal "GND6")
		(32 "In15.Cu" signal "IN6")
		(34 "In16.Cu" signal "GND7")
		(2 "B.Cu" signal "BOTTOM")
		(9 "F.Adhes" user "F.Adhesive")
		(11 "B.Adhes" user "B.Adhesive")
		(13 "F.Paste" user "Package Geometry/Pastemask Top")
		(15 "B.Paste" user "Package Geometry/Pastemask Bottom")
		(5 "F.SilkS" user "Ref Des/Silkscreen Top")
		(7 "B.SilkS" user "Ref Des/Silkscreen Bottom")
		(1 "F.Mask" user "Board Geometry/Soldermask Top")
		(3 "B.Mask" user "Board Geometry/Soldermask Bottom")
		(17 "Dwgs.User" user "User.Drawings")
		(19 "Cmts.User" user "User.Comments")
		(21 "Eco1.User" user "User.Eco1")
		(23 "Eco2.User" user "User.Eco2")
		(25 "Edge.Cuts" user "Board Geometry/Outline")
		(27 "Margin" user)
		(31 "F.CrtYd" user "Package Geometry/Place Bound Top")
		(29 "B.CrtYd" user "Package Geometry/Place Bound Bottom")
		(35 "F.Fab" user "Ref Des/Assembly Top")
		(33 "B.Fab" user "Ref Des/Assembly Bottom")
	)
	(footprint ""
		(layer "F.Cu")
		(at 57.88914 -400.755612)
		(property "Reference" "C7037"
			(at -5.0038 4.043172 0)
			(unlocked yes)
			(layer "F.SilkS")
			(effects
				(font
					(size 0.7874 0.5842)
					(thickness 0.1524)
				)
				(justify left)
			)
		)
		(property "Value" ""
			(at 0 0 0)
			(layer "F.Fab")
			(effects
				(font
					(size 1.27 1.27)
				)
			)
		)
		(duplicate_pad_numbers_are_jumpers no)
		(fp_line
			(start -4.84378 -2.150618)
			(end -4.842256 2.163064)
			(stroke
				(width 0.1524)
				(type default)
			)
			(layer "F.SilkS")
		)
		(fp_line
			(start -4.84378 -2.150618)
			(end -4.53898 -2.150618)
			(stroke
				(width 0.1524)
				(type default)
			)
			(layer "F.SilkS")
		)
		(fp_line
			(start -4.83108 2.150364)
			(end -4.447794 2.149348)
			(stroke
				(width 0.1524)
				(type default)
			)
			(layer "F.SilkS")
		)
		(fp_line
			(start -4.69138 -2.150618)
			(end -4.692396 2.161032)
			(stroke
				(width 0.1524)
				(type default)
			)
			(layer "F.SilkS")
		)
		(fp_line
			(start -4.53898 -2.150618)
			(end -4.539742 2.152142)
			(stroke
				(width 0.1524)
				(type default)
			)
			(layer "F.SilkS")
		)
		(fp_line
			(start -4.53898 -2.15011)
			(end 4.53898 -2.15011)
			(stroke
				(width 0.1524)
				(type default)
			)
			(layer "F.SilkS")
		)
		(fp_line
			(start -4.53898 2.15011)
			(end -4.53898 -2.15011)
			(stroke
				(width 0.1524)
				(type default)
			)
			(layer "F.SilkS")
		)
		(fp_line
			(start 4.53898 -2.15011)
			(end 4.53898 2.15011)
			(stroke
				(width 0.1524)
				(type default)
			)
			(layer "F.SilkS")
		)
		(fp_line
			(start 4.53898 2.15011)
			(end -4.53898 2.15011)
			(stroke
				(width 0.1524)
				(type default)
			)
			(layer "F.SilkS")
		)
		(fp_line
			(start -3.64998 -2.15011)
			(end 3.64998 -2.15011)
			(stroke
				(width 0.1)
				(type default)
			)
			(layer "F.Fab")
		)
		(fp_line
			(start -3.64998 2.15011)
			(end -3.64998 -2.15011)
			(stroke
				(width 0.1)
				(type default)
			)
			(layer "F.Fab")
		)
		(fp_line
			(start 3.64998 -2.15011)
			(end 3.64998 2.15011)
			(stroke
				(width 0.1)
				(type default)
			)
			(layer "F.Fab")
		)
		(fp_line
			(start 3.64998 2.15011)
			(end -3.64998 2.15011)
			(stroke
				(width 0.1)
				(type default)
			)
			(layer "F.Fab")
		)
		(fp_text user "+"
			(at -4.754372 2.619502 0)
			(unlocked yes)
			(layer "F.SilkS")
			(effects
				(font
					(size 1.905 1.4224)
					(thickness 0.1524)
				)
				(justify left)
			)
		)
		(fp_text user "-"
			(at 3.096514 -2.753868 0)
			(unlocked yes)
			(layer "F.SilkS")
			(effects
				(font
					(size 1.905 1.4224)
					(thickness 0.1524)
				)
				(justify left)
			)
		)
		(fp_text user "+"
			(at -6.214872 -0.337058 0)
			(unlocked yes)
			(layer "F.Fab")
			(effects
				(font
					(size 1.905 1.4224)
					(thickness 0.1524)
				)
				(justify left)
			)
		)
		(fp_text user "-"
			(at 4.313174 -0.094488 0)
			(unlocked yes)
			(layer "F.Fab")
			(effects
				(font
					(size 1.905 1.4224)
					(thickness 0.1524)
				)
				(justify left)
			)
		)
		(pad "1" smd rect
			(at -3.199892 0)
			(size 2.413 2.8194)
			(layers "F.Cu" "F.Mask" "F.Paste")
			(net "P0V9_CPU1_RT_2D")
		)
		(pad "2" smd rect
			(at 3.199892 0)
			(size 2.413 2.8194)
			(layers "F.Cu" "F.Mask" "F.Paste")
			(net "GND")
		)
	)
	(footprint ""
		(layer "F.Cu")
		(at 257.242056 -124.115068 180)
		(property "Reference" "R3707"
			(at 0 0 180)
			(layer "F.SilkS")
			(hide yes)
			(effects
				(font
					(size 1.27 1.27)
				)
			)
		)
		(property "Value" ""
			(at 0 0 180)
			(layer "F.Fab")
			(effects
				(font
					(size 1.27 1.27)
				)
			)
		)
		(duplicate_pad_numbers_are_jumpers no)
		(fp_line
			(start 0.7874 0.4064)
			(end -0.7874 0.4064)
			(stroke
				(width 0.1524)
				(type default)
			)
			(layer "F.SilkS")
		)
		(fp_line
			(start 0.7874 -0.4064)
			(end 0.7874 0.4064)
			(stroke
				(width 0.1524)
				(type default)
			)
			(layer "F.SilkS")
		)
		(fp_line
			(start -0.7874 0.4064)
			(end -0.7874 -0.4064)
			(stroke
				(width 0.1524)
				(type default)
			)
			(layer "F.SilkS")
		)
		(fp_line
			(start -0.7874 -0.4064)
			(end 0.7874 -0.4064)
			(stroke
				(width 0.1524)
				(type default)
			)
			(layer "F.SilkS")
		)
		(fp_line
			(start 0.67945 0.3048)
			(end 0.120396 0.3048)
			(stroke
				(width 0.1)
				(type default)
			)
			(layer "F.Fab")
		)
		(fp_line
			(start 0.67945 -0.3048)
			(end 0.67945 0.3048)
			(stroke
				(width 0.1)
				(type default)
			)
			(layer "F.Fab")
		)
		(fp_line
			(start 0.12065 -0.2794)
			(end 0.12065 -0.3048)
			(stroke
				(width 0.1)
				(type default)
			)
			(layer "F.Fab")
		)
		(fp_line
			(start 0.12065 -0.3048)
			(end 0.67945 -0.3048)
			(stroke
				(width 0.1)
				(type default)
			)
			(layer "F.Fab")
		)
		(fp_line
			(start 0.120396 0.3048)
			(end 0.120396 0.2794)
			(stroke
				(width 0.1)
				(type default)
			)
			(layer "F.Fab")
		)
		(fp_line
			(start 0.120396 0.2794)
			(end -0.12065 0.2794)
			(stroke
				(width 0.1)
				(type default)
			)
			(layer "F.Fab")
		)
		(fp_line
			(start -0.12065 0.3048)
			(end -0.67945 0.3048)
			(stroke
				(width 0.1)
				(type default)
			)
			(layer "F.Fab")
		)
		(fp_line
			(start -0.12065 0.2794)
			(end -0.12065 0.3048)
			(stroke
				(width 0.1)
				(type default)
			)
			(layer "F.Fab")
		)
		(fp_line
			(start -0.12065 -0.2794)
			(end 0.12065 -0.2794)
			(stroke
				(width 0.1)
				(type default)
			)
			(layer "F.Fab")
		)
		(fp_line
			(start -0.12065 -0.305054)
			(end -0.12065 -0.2794)
			(stroke
				(width 0.1)
				(type default)
			)
			(layer "F.Fab")
		)
		(fp_line
			(start -0.67945 0.3048)
			(end -0.67945 -0.305054)
			(stroke
				(width 0.1)
				(type default)
			)
			(layer "F.Fab")
		)
		(fp_line
			(start -0.67945 -0.305054)
			(end -0.12065 -0.305054)
			(stroke
				(width 0.1)
				(type default)
			)
			(layer "F.Fab")
		)
		(pad "1" smd circle
			(at -0.40005 0 180)
			(size 0 0)
			(layers "F.Cu" "F.Mask" "F.Paste")
			(net "PCA9548_PCIE0_ADDR1")
		)
		(pad "2" smd circle
			(at 0.40005 0 180)
			(size 0 0)
			(layers "F.Cu" "F.Mask" "F.Paste")
			(net "GND")
		)
	)
	(footprint ""
		(layer "F.Cu")
		(at 368.0079 -180.77561)
		(property "Reference" "PC178"
			(at 0 0 0)
			(layer "F.SilkS")
			(hide yes)
			(effects
				(font
					(size 1.27 1.27)
				)
			)
		)
		(property "Value" ""
			(at 0 0 0)
			(layer "F.Fab")
			(effects
				(font
					(size 1.27 1.27)
				)
			)
		)
		(duplicate_pad_numbers_are_jumpers no)
		(fp_line
			(start -0.7874 -0.4064)
			(end 0.7874 -0.4064)
			(stroke
				(width 0.1524)
				(type default)
			)
			(layer "F.SilkS")
		)
		(fp_line
			(start -0.7874 0.4064)
			(end -0.7874 -0.4064)
			(stroke
				(width 0.1524)
				(type default)
			)
			(layer "F.SilkS")
		)
		(fp_line
			(start 0.7874 -0.4064)
			(end 0.7874 0.4064)
			(stroke
				(width 0.1524)
				(type default)
			)
			(layer "F.SilkS")
		)
		(fp_line
			(start 0.7874 0.4064)
			(end -0.7874 0.4064)
			(stroke
				(width 0.1524)
				(type default)
			)
			(layer "F.SilkS")
		)
		(fp_line
			(start -0.67945 -0.305054)
			(end -0.12065 -0.305054)
			(stroke
				(width 0.1)
				(type default)
			)
			(layer "F.Fab")
		)
		(fp_line
			(start -0.67945 0.3048)
			(end -0.67945 -0.305054)
			(stroke
				(width 0.1)
				(type default)
			)
			(layer "F.Fab")
		)
		(fp_line
			(start -0.12065 -0.305054)
			(end -0.12065 -0.2794)
			(stroke
				(width 0.1)
				(type default)
			)
			(layer "F.Fab")
		)
		(fp_line
			(start -0.12065 -0.2794)
			(end 0.12065 -0.2794)
			(stroke
				(width 0.1)
				(type default)
			)
			(layer "F.Fab")
		)
		(fp_line
			(start -0.12065 0.2794)
			(end -0.12065 0.3048)
			(stroke
				(width 0.1)
				(type default)
			)
			(layer "F.Fab")
		)
		(fp_line
			(start -0.12065 0.3048)
			(end -0.67945 0.3048)
			(stroke
				(width 0.1)
				(type default)
			)
			(layer "F.Fab")
		)
		(fp_line
			(start 0.120396 0.2794)
			(end -0.12065 0.2794)
			(stroke
				(width 0.1)
				(type default)
			)
			(layer "F.Fab")
		)
		(fp_line
			(start 0.120396 0.3048)
			(end 0.120396 0.2794)
			(stroke
				(width 0.1)
				(type default)
			)
			(layer "F.Fab")
		)
		(fp_line
			(start 0.12065 -0.3048)
			(end 0.67945 -0.3048)
			(stroke
				(width 0.1)
				(type default)
			)
			(layer "F.Fab")
		)
		(fp_line
			(start 0.12065 -0.2794)
			(end 0.12065 -0.3048)
			(stroke
				(width 0.1)
				(type default)
			)
			(layer "F.Fab")
		)
		(fp_line
			(start 0.67945 -0.3048)
			(end 0.67945 0.3048)
			(stroke
				(width 0.1)
				(type default)
			)
			(layer "F.Fab")
		)
		(fp_line
			(start 0.67945 0.3048)
			(end 0.120396 0.3048)
			(stroke
				(width 0.1)
				(type default)
			)
			(layer "F.Fab")
		)
		(pad "1" smd circle
			(at -0.40005 0)
			(size 0 0)
			(layers "F.Cu" "F.Mask" "F.Paste")
			(net "SW_PVDDCR_CPU0_P0_SW1")
		)
		(pad "2" smd circle
			(at 0.40005 0)
			(size 0 0)
			(layers "F.Cu" "F.Mask" "F.Paste")
			(net "SW_PVDDCR_CPU0_P0_SW1_RC")
		)
	)
	(footprint ""
		(layer "F.Cu")
		(at 24.765 -367.919)
		(property "Reference" "R8249"
			(at 0 0 0)
			(layer "F.SilkS")
			(hide yes)
			(effects
				(font
					(size 1.27 1.27)
				)
			)
		)
		(property "Value" ""
			(at 0 0 0)
			(layer "F.Fab")
			(effects
				(font
					(size 1.27 1.27)
				)
			)
		)
		(duplicate_pad_numbers_are_jumpers no)
		(fp_line
			(start -0.7874 -0.4064)
			(end 0.7874 -0.4064)
			(stroke
				(width 0.1524)
				(type default)
			)
			(layer "F.SilkS")
		)
		(fp_line
			(start -0.7874 0.4064)
			(end -0.7874 -0.4064)
			(stroke
				(width 0.1524)
				(type default)
			)
			(layer "F.SilkS")
		)
		(fp_line
			(start 0.7874 -0.4064)
			(end 0.7874 0.4064)
			(stroke
				(width 0.1524)
				(type default)
			)
			(layer "F.SilkS")
		)
		(fp_line
			(start 0.7874 0.4064)
			(end -0.7874 0.4064)
			(stroke
				(width 0.1524)
				(type default)
			)
			(layer "F.SilkS")
		)
		(fp_line
			(start -0.67945 -0.305054)
			(end -0.12065 -0.305054)
			(stroke
				(width 0.1)
				(type default)
			)
			(layer "F.Fab")
		)
		(fp_line
			(start -0.67945 0.3048)
			(end -0.67945 -0.305054)
			(stroke
				(width 0.1)
				(type default)
			)
			(layer "F.Fab")
		)
		(fp_line
			(start -0.12065 -0.305054)
			(end -0.12065 -0.2794)
			(stroke
				(width 0.1)
				(type default)
			)
			(layer "F.Fab")
		)
		(fp_line
			(start -0.12065 -0.2794)
			(end 0.12065 -0.2794)
			(stroke
				(width 0.1)
				(type default)
			)
			(layer "F.Fab")
		)
		(fp_line
			(start -0.12065 0.2794)
			(end -0.12065 0.3048)
			(stroke
				(width 0.1)
				(type default)
			)
			(layer "F.Fab")
		)
		(fp_line
			(start -0.12065 0.3048)
			(end -0.67945 0.3048)
			(stroke
				(width 0.1)
				(type default)
			)
			(layer "F.Fab")
		)
		(fp_line
			(start 0.120396 0.2794)
			(end -0.12065 0.2794)
			(stroke
				(width 0.1)
				(type default)
			)
			(layer "F.Fab")
		)
		(fp_line
			(start 0.120396 0.3048)
			(end 0.120396 0.2794)
			(stroke
				(width 0.1)
				(type default)
			)
			(layer "F.Fab")
		)
		(fp_line
			(start 0.12065 -0.3048)
			(end 0.67945 -0.3048)
			(stroke
				(width 0.1)
				(type default)
			)
			(layer "F.Fab")
		)
		(fp_line
			(start 0.12065 -0.2794)
			(end 0.12065 -0.3048)
			(stroke
				(width 0.1)
				(type default)
			)
			(layer "F.Fab")
		)
		(fp_line
			(start 0.67945 -0.3048)
			(end 0.67945 0.3048)
			(stroke
				(width 0.1)
				(type default)
			)
			(layer "F.Fab")
		)
		(fp_line
			(start 0.67945 0.3048)
			(end 0.120396 0.3048)
			(stroke
				(width 0.1)
				(type default)
			)
			(layer "F.Fab")
		)
		(pad "1" smd circle
			(at -0.40005 0)
			(size 0 0)
			(layers "F.Cu" "F.Mask" "F.Paste")
			(net "SMB_SCM_2_R1_SDA")
		)
		(pad "2" smd circle
			(at 0.40005 0)
			(size 0 0)
			(layers "F.Cu" "F.Mask" "F.Paste")
			(net "SMB_DIO_PVDDCR_CPU1_P1_R")
		)
	)
	(footprint ""
		(layer "F.Cu")
		(at 117.931946 -408.517344 -90)
		(property "Reference" "C6696"
			(at 0 0 270)
			(layer "F.SilkS")
			(hide yes)
			(effects
				(font
					(size 1.27 1.27)
				)
			)
		)
		(property "Value" ""
			(at 0 0 270)
			(layer "F.Fab")
			(effects
				(font
					(size 1.27 1.27)
				)
			)
		)
		(duplicate_pad_numbers_are_jumpers no)
		(fp_line
			(start -0.299974 0.150114)
			(end -0.299974 -0.150114)
			(stroke
				(width 0.1)
				(type default)
			)
			(layer "F.Fab")
		)
		(fp_line
			(start 0.299974 0.150114)
			(end -0.299974 0.150114)
			(stroke
				(width 0.1)
				(type default)
			)
			(layer "F.Fab")
		)
		(fp_line
			(start -0.299974 -0.150114)
			(end 0.299974 -0.150114)
			(stroke
				(width 0.1)
				(type default)
			)
			(layer "F.Fab")
		)
		(fp_line
			(start 0.299974 -0.150114)
			(end 0.299974 0.150114)
			(stroke
				(width 0.1)
				(type default)
			)
			(layer "F.Fab")
		)
		(pad "1" smd rect
			(at -0.2667 0 270)
			(size 0.3048 0.381)
			(layers "F.Cu" "F.Mask" "F.Paste")
			(net "P5E_CPU1_P2_TX_BUF_C_DN<1>")
		)
		(pad "2" smd rect
			(at 0.2667 0 270)
			(size 0.3048 0.381)
			(layers "F.Cu" "F.Mask" "F.Paste")
			(net "P5E_CPU1_P2_TX_BUF_DN<1>")
		)
	)
	(footprint ""
		(layer "F.Cu")
		(at 193.03238 -355.924358 -90)
		(property "Reference" "PC520"
			(at 0 0 270)
			(layer "F.SilkS")
			(hide yes)
			(effects
				(font
					(size 1.27 1.27)
				)
			)
		)
		(property "Value" ""
			(at 0 0 270)
			(layer "F.Fab")
			(effects
				(font
					(size 1.27 1.27)
				)
			)
		)
		(duplicate_pad_numbers_are_jumpers no)
		(fp_line
			(start -0.7874 0.4064)
			(end -0.7874 -0.4064)
			(stroke
				(width 0.1524)
				(type default)
			)
			(layer "F.SilkS")
		)
		(fp_line
			(start 0.7874 0.4064)
			(end -0.7874 0.4064)
			(stroke
				(width 0.1524)
				(type default)
			)
			(layer "F.SilkS")
		)
		(fp_line
			(start -0.7874 -0.4064)
			(end 0.7874 -0.4064)
			(stroke
				(width 0.1524)
				(type default)
			)
			(layer "F.SilkS")
		)
		(fp_line
			(start 0.7874 -0.4064)
			(end 0.7874 0.4064)
			(stroke
				(width 0.1524)
				(type default)
			)
			(layer "F.SilkS")
		)
		(fp_line
			(start -0.67945 0.3048)
			(end -0.67945 -0.305054)
			(stroke
				(width 0.1)
				(type default)
			)
			(layer "F.Fab")
		)
		(fp_line
			(start -0.12065 0.3048)
			(end -0.67945 0.3048)
			(stroke
				(width 0.1)
				(type default)
			)
			(layer "F.Fab")
		)
		(fp_line
			(start 0.120396 0.3048)
			(end 0.120396 0.2794)
			(stroke
				(width 0.1)
				(type default)
			)
			(layer "F.Fab")
		)
		(fp_line
			(start 0.67945 0.3048)
			(end 0.120396 0.3048)
			(stroke
				(width 0.1)
				(type default)
			)
			(layer "F.Fab")
		)
		(fp_line
			(start -0.12065 0.2794)
			(end -0.12065 0.3048)
			(stroke
				(width 0.1)
				(type default)
			)
			(layer "F.Fab")
		)
		(fp_line
			(start 0.120396 0.2794)
			(end -0.12065 0.2794)
			(stroke
				(width 0.1)
				(type default)
			)
			(layer "F.Fab")
		)
		(fp_line
			(start -0.12065 -0.2794)
			(end 0.12065 -0.2794)
			(stroke
				(width 0.1)
				(type default)
			)
			(layer "F.Fab")
		)
		(fp_line
			(start 0.12065 -0.2794)
			(end 0.12065 -0.3048)
			(stroke
				(width 0.1)
				(type default)
			)
			(layer "F.Fab")
		)
		(fp_line
			(start 0.12065 -0.3048)
			(end 0.67945 -0.3048)
			(stroke
				(width 0.1)
				(type default)
			)
			(layer "F.Fab")
		)
		(fp_line
			(start 0.67945 -0.3048)
			(end 0.67945 0.3048)
			(stroke
				(width 0.1)
				(type default)
			)
			(layer "F.Fab")
		)
		(fp_line
			(start -0.67945 -0.305054)
			(end -0.12065 -0.305054)
			(stroke
				(width 0.1)
				(type default)
			)
			(layer "F.Fab")
		)
		(fp_line
			(start -0.12065 -0.305054)
			(end -0.12065 -0.2794)
			(stroke
				(width 0.1)
				(type default)
			)
			(layer "F.Fab")
		)
		(pad "1" smd circle
			(at -0.40005 0 270)
			(size 0 0)
			(layers "F.Cu" "F.Mask" "F.Paste")
			(net "SW_PVDD11_S3_P1_BOOT2_RC")
		)
		(pad "2" smd circle
			(at 0.40005 0 270)
			(size 0 0)
			(layers "F.Cu" "F.Mask" "F.Paste")
			(net "SW_PVDD11_S3_P1_PH2")
		)
	)
)
